# TIMECARD (Time Appliance Project (Time Card)) — schematic netlist excerpt (pin names and nets, part order shuffled) for the footprints in the layout excerpt that follows; sources: Cadence DE-HDL packaged netlist, KiCad conversion of R4006-B0001-02_R01.brd

U37  TS3A5018PWR_TSSOP16  pkg SOP16_173_P0256  page 24
  \in\  = MUX3_SEL
  NC1  = FPGA_PCA9546_I2C_SDA
  NO1  = FT4232_I2C_SDA
  COM1  = PCA9546_I2C_SDA
  NC2  = FPGA_PCA9546_I2C_SCL
  NO2  = FT4232_I2C_SCL
  COM2  = PCA9546_I2C_SCL
  GND  = SG
  COM3  = EEPROM_I2C_SDA
  NO3  = FT4232_I2C_SDA
  NC3  = FPGA_EEPROM_I2C_SDA
  COM4  = EEPROM_I2C_SCL
  NO4  = FT4232_I2C_SCL
  NC4  = FPGA_EEPROM_I2C_SCL
  \en*\  = UNNAMED_524_RESISTOR_I463_2
  V_P  = XP3R3V_FPGA

TP193  TP_PIONT  pkg TP010CT020B030_PTH  page 25 : \1\ = IO_L21P_35

(kicad_pcb
	(version 20260206)
	(generator "pcbnew")
	(generator_version "10.0")
	(general
		(thickness 1.6)
		(legacy_teardrops no)
	)
	(paper "A4")
	(title_block
		(title "timecard-production-celestica-r4006 — R4006-B0001-02_R01.brd")
		(comment 1 "Time Appliance Project (Time Card) / footprints 309-310 of 1113")
	)
	(layers
		(0 "F.Cu" signal "TOP")
		(4 "In1.Cu" signal "L02_GND1")
		(6 "In2.Cu" signal "L03_SIG1")
		(8 "In3.Cu" signal "L04_GND2")
		(10 "In4.Cu" signal "L05_VCC1")
		(12 "In5.Cu" signal "L06_VCC2")
		(14 "In6.Cu" signal "L07_GND3")
		(16 "In7.Cu" signal "L08_SIG2")
		(18 "In8.Cu" signal "L09_GND4")
		(2 "B.Cu" signal "BOTTOM")
		(9 "F.Adhes" user "F.Adhesive")
		(11 "B.Adhes" user "B.Adhesive")
		(13 "F.Paste" user "Package Geometry/Pastemask Top")
		(15 "B.Paste" user "Package Geometry/Pastemask Bottom")
		(5 "F.SilkS" user "Ref Des/Silkscreen Top")
		(7 "B.SilkS" user "Ref Des/Silkscreen Bottom")
		(1 "F.Mask" user "Board Geometry/Soldermask Top")
		(3 "B.Mask" user "Board Geometry/Soldermask Bottom")
		(17 "Dwgs.User" user "User.Drawings")
		(19 "Cmts.User" user "User.Comments")
		(21 "Eco1.User" user "User.Eco1")
		(23 "Eco2.User" user "User.Eco2")
		(25 "Edge.Cuts" user "Board Geometry/Outline")
		(27 "Margin" user)
		(31 "F.CrtYd" user "Package Geometry/Place Bound Top")
		(29 "B.CrtYd" user "Package Geometry/Place Bound Bottom")
		(35 "F.Fab" user "Ref Des/Assembly Top")
		(33 "B.Fab" user "Ref Des/Assembly Bottom")
	)
	(footprint ""
		(layer "F.Cu")
		(at 127.127 -21.082)
		(property "Reference" "U37"
			(at -0.889 -3.64363 0)
			(unlocked yes)
			(layer "F.SilkS")
			(effects
				(font
					(size 0.7874 0.5842)
					(thickness 0.1524)
				)
			)
		)
		(property "Value" ""
			(at 0 0 0)
			(layer "F.Fab")
			(effects
				(font
					(size 1.27 1.27)
				)
			)
		)
		(property "Device Type" "TS3A5018PWR_TSSOP16-G220-10324A"
			(at 0 0.924306 0)
			(unlocked yes)
			(layer "F.Fab")
			(hide yes)
			(effects
				(font
					(size 0.7874 0.5842)
					(thickness 0.000001)
				)
			)
		)
		(property "User Part Number" "PARTNUM*"
			(at 0.254 1.940306 0)
			(unlocked yes)
			(layer "Cmts.User")
			(hide yes)
			(effects
				(font
					(size 0.7874 0.5842)
					(thickness 0.000001)
				)
			)
		)
		(duplicate_pad_numbers_are_jumpers no)
		(fp_line
			(start -4.0767 -2.7559)
			(end 4.0767 -2.7559)
			(stroke
				(width 0.1)
				(type default)
			)
			(layer "F.SilkS")
		)
		(fp_line
			(start -4.0767 2.7559)
			(end -4.0767 -2.7559)
			(stroke
				(width 0.1)
				(type default)
			)
			(layer "F.SilkS")
		)
		(fp_line
			(start 4.0767 -2.7559)
			(end 4.0767 2.7559)
			(stroke
				(width 0.1)
				(type default)
			)
			(layer "F.SilkS")
		)
		(fp_line
			(start 4.0767 2.7559)
			(end -4.0767 2.7559)
			(stroke
				(width 0.1)
				(type default)
			)
			(layer "F.SilkS")
		)
		(fp_poly
			(pts
				(arc
					(start -3.937 -3.175)
					(mid -4.699 -3.175)
					(end -3.937 -3.175)
				)
			)
			(stroke
				(width 0)
				(type default)
			)
			(fill yes)
			(layer "F.SilkS")
		)
		(fp_rect
			(start -4.3307 3.0099)
			(end 4.3307 -3.0099)
			(stroke
				(width 0)
				(type default)
			)
			(fill no)
			(layer "F.CrtYd")
		)
		(fp_line
			(start -2.1971 -2.5019)
			(end 2.1971 -2.5019)
			(stroke
				(width 0.1)
				(type default)
			)
			(layer "F.Fab")
		)
		(fp_line
			(start -2.1971 2.5019)
			(end -2.1971 -2.5019)
			(stroke
				(width 0.1)
				(type default)
			)
			(layer "F.Fab")
		)
		(fp_line
			(start 2.1971 -2.5019)
			(end 2.1971 2.5019)
			(stroke
				(width 0.1)
				(type default)
			)
			(layer "F.Fab")
		)
		(fp_line
			(start 2.1971 2.5019)
			(end -2.1971 2.5019)
			(stroke
				(width 0.1)
				(type default)
			)
			(layer "F.Fab")
		)
		(fp_poly
			(pts
				(arc
					(start -1.114298 -1.942084)
					(mid -1.914398 -1.942084)
					(end -1.114298 -1.942084)
				)
			)
			(stroke
				(width 0)
				(type default)
			)
			(fill yes)
			(layer "F.Fab")
		)
		(fp_text user "8"
			(at -4.572 2.18567 0)
			(unlocked yes)
			(layer "F.SilkS")
			(effects
				(font
					(size 0.7874 0.5842)
					(thickness 0.1524)
				)
			)
		)
		(fp_text user "16"
			(at 4.064 -3.64363 0)
			(unlocked yes)
			(layer "F.SilkS")
			(effects
				(font
					(size 0.7874 0.5842)
					(thickness 0.1524)
				)
			)
		)
		(fp_text user "9"
			(at 4.699 2.96037 0)
			(unlocked yes)
			(layer "F.SilkS")
			(effects
				(font
					(size 0.7874 0.5842)
					(thickness 0.1524)
				)
			)
		)
		(fp_text user "8"
			(at -4.572 2.18567 0)
			(unlocked yes)
			(layer "F.Fab")
			(effects
				(font
					(size 0.7874 0.5842)
					(thickness 0.1524)
				)
			)
		)
		(fp_text user "9"
			(at 4.5466 2.31267 0)
			(unlocked yes)
			(layer "F.Fab")
			(effects
				(font
					(size 0.7874 0.5842)
					(thickness 0.1524)
				)
			)
		)
		(fp_text user "16"
			(at 4.8768 -2.38633 0)
			(unlocked yes)
			(layer "F.Fab")
			(effects
				(font
					(size 0.7874 0.5842)
					(thickness 0.1524)
				)
			)
		)
		(pad "1" smd rect
			(at -3.0353 -2.275078 90)
			(size 0.3556 1.5748)
			(layers "F.Cu" "F.Mask" "F.Paste")
			(net "MUX3_SEL")
		)
		(pad "2" smd rect
			(at -3.0353 -1.625092 90)
			(size 0.3556 1.5748)
			(layers "F.Cu" "F.Mask" "F.Paste")
			(net "FPGA_PCA9546_I2C_SDA")
		)
		(pad "3" smd rect
			(at -3.0353 -0.975106 90)
			(size 0.3556 1.5748)
			(layers "F.Cu" "F.Mask" "F.Paste")
			(net "FT4232_I2C_SDA")
		)
		(pad "4" smd rect
			(at -3.0353 -0.32512 90)
			(size 0.3556 1.5748)
			(layers "F.Cu" "F.Mask" "F.Paste")
			(net "PCA9546_I2C_SDA")
		)
		(pad "5" smd rect
			(at -3.0353 0.32512 90)
			(size 0.3556 1.5748)
			(layers "F.Cu" "F.Mask" "F.Paste")
			(net "FPGA_PCA9546_I2C_SCL")
		)
		(pad "6" smd rect
			(at -3.0353 0.975106 90)
			(size 0.3556 1.5748)
			(layers "F.Cu" "F.Mask" "F.Paste")
			(net "FT4232_I2C_SCL")
		)
		(pad "7" smd rect
			(at -3.0353 1.625092 90)
			(size 0.3556 1.5748)
			(layers "F.Cu" "F.Mask" "F.Paste")
			(net "PCA9546_I2C_SCL")
		)
		(pad "8" smd rect
			(at -3.0353 2.275078 90)
			(size 0.3556 1.5748)
			(layers "F.Cu" "F.Mask" "F.Paste")
			(net "SG")
		)
		(pad "9" smd rect
			(at 3.0353 2.275078 90)
			(size 0.3556 1.5748)
			(layers "F.Cu" "F.Mask" "F.Paste")
			(net "EEPROM_I2C_SDA")
		)
		(pad "10" smd rect
			(at 3.0353 1.625092 90)
			(size 0.3556 1.5748)
			(layers "F.Cu" "F.Mask" "F.Paste")
			(net "FT4232_I2C_SDA")
		)
		(pad "11" smd rect
			(at 3.0353 0.975106 90)
			(size 0.3556 1.5748)
			(layers "F.Cu" "F.Mask" "F.Paste")
			(net "FPGA_EEPROM_I2C_SDA")
		)
		(pad "12" smd rect
			(at 3.0353 0.32512 90)
			(size 0.3556 1.5748)
			(layers "F.Cu" "F.Mask" "F.Paste")
			(net "EEPROM_I2C_SCL")
		)
		(pad "13" smd rect
			(at 3.0353 -0.32512 90)
			(size 0.3556 1.5748)
			(layers "F.Cu" "F.Mask" "F.Paste")
			(net "FT4232_I2C_SCL")
		)
		(pad "14" smd rect
			(at 3.0353 -0.975106 90)
			(size 0.3556 1.5748)
			(layers "F.Cu" "F.Mask" "F.Paste")
			(net "FPGA_EEPROM_I2C_SCL")
		)
		(pad "15" smd rect
			(at 3.0353 -1.625092 90)
			(size 0.3556 1.5748)
			(layers "F.Cu" "F.Mask" "F.Paste")
			(net "UNNAMED_524_RESISTOR_I463_2")
		)
		(pad "16" smd rect
			(at 3.0353 -2.275078 90)
			(size 0.3556 1.5748)
			(layers "F.Cu" "F.Mask" "F.Paste")
			(net "XP3R3V_FPGA")
		)
	)
	(footprint ""
		(layer "F.Cu")
		(at 121.1072 -30.6578 90)
		(property "Reference" "TP193"
			(at -1.35255 0 0)
			(unlocked yes)
			(layer "F.SilkS")
			(effects
				(font
					(size 0.635 0.4064)
					(thickness 0.1524)
				)
				(justify left)
			)
		)
		(property "Value" ""
			(at 0 0 90)
			(layer "F.Fab")
			(effects
				(font
					(size 1.27 1.27)
				)
			)
		)
		(property "Device Type" "TP_PIONT-TP010CT020B030_PTH-TPA"
			(at -1.341882 0.996696 90)
			(unlocked yes)
			(layer "F.Fab")
			(hide yes)
			(effects
				(font
					(size 0.7874 0.5842)
					(thickness 0.1524)
				)
				(justify left)
			)
		)
		(duplicate_pad_numbers_are_jumpers no)
		(fp_poly
			(pts
				(arc
					(start 0 0.889)
					(mid 0 -0.889)
					(end 0 0.889)
				)
			)
			(stroke
				(width 0)
				(type default)
			)
			(fill no)
			(layer "B.CrtYd")
		)
		(fp_poly
			(pts
				(arc
					(start 0 0.889)
					(mid 0 -0.889)
					(end 0 0.889)
				)
			)
			(stroke
				(width 0)
				(type default)
			)
			(fill no)
			(layer "F.CrtYd")
		)
		(pad "1" thru_hole circle
			(at 0 0 90)
			(size 0.508 0.508)
			(drill 0.254)
			(layers "*.Cu" "*.Mask")
			(remove_unused_layers no)
			(net "IO_L21P_35")
			(clearance 0.1016)
			(padstack
				(mode front_inner_back)
				(layer "Inner"
					(shape circle)
					(size 0.508 0.508)
					(clearance 0.1016)
				)
				(layer "B.Cu"
					(shape circle)
					(size 0.762 0.762)
					(clearance -0.0254)
				)
			)
		)
	)
)
